# SCM (Grand Teton) — schematic netlist excerpt (pin names and nets, part order shuffled) for the footprints in the layout excerpt that follows; sources: Cadence DE-HDL packaged netlist, KiCad conversion of 12092022_DA0F0TMDCD0_F0T_Management_Board_D_brd_V3_OCP.brd

C235  Q_CAP  0.1UF 25V 10% EMPTY  pkg 0402  page 21 : A = P3V3_AUX ; B = GND
R78  Q_RES  2K 1% CHIP  pkg 0402LF  page 11 : A = P3V3_AUX ; B = SGPIO_DI_0

(kicad_pcb
	(version 20260206)
	(generator "pcbnew")
	(generator_version "10.0")
	(general
		(thickness 1.6)
		(legacy_teardrops no)
	)
	(paper "A4")
	(title_block
		(title "12092022_DA0F0TMDCD0_F0T_Management_Board_D_brd_V3_OCP.brd")
		(comment 1 "Grand Teton / footprints 669-670 of 1440")
	)
	(layers
		(0 "F.Cu" signal "TOP")
		(4 "In1.Cu" signal "GND")
		(6 "In2.Cu" signal "IN1")
		(8 "In3.Cu" signal "GND1")
		(10 "In4.Cu" signal "IN2")
		(12 "In5.Cu" signal "VCC")
		(14 "In6.Cu" signal "VCC1")
		(16 "In7.Cu" signal "IN3")
		(18 "In8.Cu" signal "GND2")
		(20 "In9.Cu" signal "IN4")
		(22 "In10.Cu" signal "GND3")
		(2 "B.Cu" signal "BOTTOM")
		(9 "F.Adhes" user "F.Adhesive")
		(11 "B.Adhes" user "B.Adhesive")
		(13 "F.Paste" user "Package Geometry/Pastemask Top")
		(15 "B.Paste" user "Package Geometry/Pastemask Bottom")
		(5 "F.SilkS" user "Ref Des/Silkscreen Top")
		(7 "B.SilkS" user "Ref Des/Silkscreen Bottom")
		(1 "F.Mask" user "Board Geometry/Soldermask Top")
		(3 "B.Mask" user "Board Geometry/Soldermask Bottom")
		(17 "Dwgs.User" user "User.Drawings")
		(19 "Cmts.User" user "User.Comments")
		(21 "Eco1.User" user "User.Eco1")
		(23 "Eco2.User" user "User.Eco2")
		(25 "Edge.Cuts" user "Board Geometry/Outline")
		(27 "Margin" user)
		(31 "F.CrtYd" user "Package Geometry/Place Bound Top")
		(29 "B.CrtYd" user "Package Geometry/Place Bound Bottom")
		(35 "F.Fab" user "Ref Des/Assembly Top")
		(33 "B.Fab" user "Ref Des/Assembly Bottom")
	)
	(footprint ""
		(layer "F.Cu")
		(at 18.923 -69.977 -90)
		(property "Reference" "C235"
			(at 0 0 270)
			(layer "F.SilkS")
			(hide yes)
			(effects
				(font
					(size 1.27 1.27)
				)
			)
		)
		(property "Value" ""
			(at 0 0 270)
			(layer "F.Fab")
			(effects
				(font
					(size 1.27 1.27)
				)
			)
		)
		(duplicate_pad_numbers_are_jumpers no)
		(fp_line
			(start -0.7874 0.4064)
			(end -0.7874 -0.4064)
			(stroke
				(width 0.1524)
				(type default)
			)
			(layer "F.SilkS")
		)
		(fp_line
			(start 0.7874 0.4064)
			(end -0.7874 0.4064)
			(stroke
				(width 0.1524)
				(type default)
			)
			(layer "F.SilkS")
		)
		(fp_line
			(start -0.7874 -0.4064)
			(end 0.7874 -0.4064)
			(stroke
				(width 0.1524)
				(type default)
			)
			(layer "F.SilkS")
		)
		(fp_line
			(start 0.7874 -0.4064)
			(end 0.7874 0.4064)
			(stroke
				(width 0.1524)
				(type default)
			)
			(layer "F.SilkS")
		)
		(fp_line
			(start -0.67945 0.3048)
			(end -0.67945 -0.305054)
			(stroke
				(width 0.1)
				(type default)
			)
			(layer "F.Fab")
		)
		(fp_line
			(start -0.12065 0.3048)
			(end -0.67945 0.3048)
			(stroke
				(width 0.1)
				(type default)
			)
			(layer "F.Fab")
		)
		(fp_line
			(start 0.120396 0.3048)
			(end 0.120396 0.2794)
			(stroke
				(width 0.1)
				(type default)
			)
			(layer "F.Fab")
		)
		(fp_line
			(start 0.67945 0.3048)
			(end 0.120396 0.3048)
			(stroke
				(width 0.1)
				(type default)
			)
			(layer "F.Fab")
		)
		(fp_line
			(start -0.12065 0.2794)
			(end -0.12065 0.3048)
			(stroke
				(width 0.1)
				(type default)
			)
			(layer "F.Fab")
		)
		(fp_line
			(start 0.120396 0.2794)
			(end -0.12065 0.2794)
			(stroke
				(width 0.1)
				(type default)
			)
			(layer "F.Fab")
		)
		(fp_line
			(start -0.12065 -0.2794)
			(end 0.12065 -0.2794)
			(stroke
				(width 0.1)
				(type default)
			)
			(layer "F.Fab")
		)
		(fp_line
			(start 0.12065 -0.2794)
			(end 0.12065 -0.3048)
			(stroke
				(width 0.1)
				(type default)
			)
			(layer "F.Fab")
		)
		(fp_line
			(start 0.12065 -0.3048)
			(end 0.67945 -0.3048)
			(stroke
				(width 0.1)
				(type default)
			)
			(layer "F.Fab")
		)
		(fp_line
			(start 0.67945 -0.3048)
			(end 0.67945 0.3048)
			(stroke
				(width 0.1)
				(type default)
			)
			(layer "F.Fab")
		)
		(fp_line
			(start -0.67945 -0.305054)
			(end -0.12065 -0.305054)
			(stroke
				(width 0.1)
				(type default)
			)
			(layer "F.Fab")
		)
		(fp_line
			(start -0.12065 -0.305054)
			(end -0.12065 -0.2794)
			(stroke
				(width 0.1)
				(type default)
			)
			(layer "F.Fab")
		)
		(pad "1" smd circle
			(at -0.40005 0 270)
			(size 0 0)
			(layers "F.Cu" "F.Mask" "F.Paste")
			(net "P3V3_AUX")
		)
		(pad "2" smd circle
			(at 0.40005 0 270)
			(size 0 0)
			(layers "F.Cu" "F.Mask" "F.Paste")
			(net "GND")
		)
	)
	(footprint ""
		(layer "F.Cu")
		(at 41.0083 -109.474 -90)
		(property "Reference" "R78"
			(at 0 0 270)
			(layer "F.SilkS")
			(hide yes)
			(effects
				(font
					(size 1.27 1.27)
				)
			)
		)
		(property "Value" ""
			(at 0 0 270)
			(layer "F.Fab")
			(effects
				(font
					(size 1.27 1.27)
				)
			)
		)
		(duplicate_pad_numbers_are_jumpers no)
		(fp_line
			(start -0.7874 0.4064)
			(end -0.7874 -0.4064)
			(stroke
				(width 0.1524)
				(type default)
			)
			(layer "F.SilkS")
		)
		(fp_line
			(start 0.7874 0.4064)
			(end -0.7874 0.4064)
			(stroke
				(width 0.1524)
				(type default)
			)
			(layer "F.SilkS")
		)
		(fp_line
			(start -0.7874 -0.4064)
			(end 0.7874 -0.4064)
			(stroke
				(width 0.1524)
				(type default)
			)
			(layer "F.SilkS")
		)
		(fp_line
			(start 0.7874 -0.4064)
			(end 0.7874 0.4064)
			(stroke
				(width 0.1524)
				(type default)
			)
			(layer "F.SilkS")
		)
		(fp_line
			(start -0.67945 0.3048)
			(end -0.67945 -0.305054)
			(stroke
				(width 0.1)
				(type default)
			)
			(layer "F.Fab")
		)
		(fp_line
			(start -0.12065 0.3048)
			(end -0.67945 0.3048)
			(stroke
				(width 0.1)
				(type default)
			)
			(layer "F.Fab")
		)
		(fp_line
			(start 0.120396 0.3048)
			(end 0.120396 0.2794)
			(stroke
				(width 0.1)
				(type default)
			)
			(layer "F.Fab")
		)
		(fp_line
			(start 0.67945 0.3048)
			(end 0.120396 0.3048)
			(stroke
				(width 0.1)
				(type default)
			)
			(layer "F.Fab")
		)
		(fp_line
			(start -0.12065 0.2794)
			(end -0.12065 0.3048)
			(stroke
				(width 0.1)
				(type default)
			)
			(layer "F.Fab")
		)
		(fp_line
			(start 0.120396 0.2794)
			(end -0.12065 0.2794)
			(stroke
				(width 0.1)
				(type default)
			)
			(layer "F.Fab")
		)
		(fp_line
			(start -0.12065 -0.2794)
			(end 0.12065 -0.2794)
			(stroke
				(width 0.1)
				(type default)
			)
			(layer "F.Fab")
		)
		(fp_line
			(start 0.12065 -0.2794)
			(end 0.12065 -0.3048)
			(stroke
				(width 0.1)
				(type default)
			)
			(layer "F.Fab")
		)
		(fp_line
			(start 0.12065 -0.3048)
			(end 0.67945 -0.3048)
			(stroke
				(width 0.1)
				(type default)
			)
			(layer "F.Fab")
		)
		(fp_line
			(start 0.67945 -0.3048)
			(end 0.67945 0.3048)
			(stroke
				(width 0.1)
				(type default)
			)
			(layer "F.Fab")
		)
		(fp_line
			(start -0.67945 -0.305054)
			(end -0.12065 -0.305054)
			(stroke
				(width 0.1)
				(type default)
			)
			(layer "F.Fab")
		)
		(fp_line
			(start -0.12065 -0.305054)
			(end -0.12065 -0.2794)
			(stroke
				(width 0.1)
				(type default)
			)
			(layer "F.Fab")
		)
		(pad "1" smd circle
			(at -0.40005 0 270)
			(size 0 0)
			(layers "F.Cu" "F.Mask" "F.Paste")
			(net "P3V3_AUX")
		)
		(pad "2" smd circle
			(at 0.40005 0 270)
			(size 0 0)
			(layers "F.Cu" "F.Mask" "F.Paste")
			(net "SGPIO_DI_0")
		)
	)
)
